(kicad_pcb
	(version 20260206)
	(generator "pcbnew")
	(generator_version "10.0")
	(general
		(thickness 1.6)
		(legacy_teardrops no)
	)
	(paper "A4")
	(title_block
		(title "Wiwynn_Tioga_Pass_MB.brd")
		(comment 1 "Tioga Pass / footprints 3923-3930 of 4770")
	)
	(layers
		(0 "F.Cu" signal "TOP")
		(4 "In1.Cu" signal "L2GND")
		(6 "In2.Cu" signal "L3")
		(8 "In3.Cu" signal "L4GND")
		(10 "In4.Cu" signal "L5")
		(12 "In5.Cu" signal "L6GND")
		(14 "In6.Cu" signal "L7VCC")
		(16 "In7.Cu" signal "L8VCC")
		(18 "In8.Cu" signal "L9GND")
		(20 "In9.Cu" signal "L10")
		(22 "In10.Cu" signal "L11GND")
		(24 "In11.Cu" signal "L12")
		(26 "In12.Cu" signal "L13GND")
		(2 "B.Cu" signal "BOTTOM")
		(9 "F.Adhes" user "F.Adhesive")
		(11 "B.Adhes" user "B.Adhesive")
		(13 "F.Paste" user "Package Geometry/Pastemask Top")
		(15 "B.Paste" user "Package Geometry/Pastemask Bottom")
		(5 "F.SilkS" user "Ref Des/Silkscreen Top")
		(7 "B.SilkS" user "Ref Des/Silkscreen Bottom")
		(1 "F.Mask" user "Board Geometry/Soldermask Top")
		(3 "B.Mask" user "Board Geometry/Soldermask Bottom")
		(17 "Dwgs.User" user "User.Drawings")
		(19 "Cmts.User" user "User.Comments")
		(21 "Eco1.User" user "User.Eco1")
		(23 "Eco2.User" user "User.Eco2")
		(25 "Edge.Cuts" user "Board Geometry/Outline")
		(27 "Margin" user)
		(31 "F.CrtYd" user "Package Geometry/Place Bound Top")
		(29 "B.CrtYd" user "Package Geometry/Place Bound Bottom")
		(35 "F.Fab" user "Ref Des/Assembly Top")
		(33 "B.Fab" user "Ref Des/Assembly Bottom")
	)
	(footprint ""
		(layer "B.Cu")
		(at 485.734868 -121.774712 180)
		(property "Reference" "C9B9"
			(at 0 0 0)
			(layer "B.SilkS")
			(hide yes)
			(effects
				(font
					(size 1.27 1.27)
				)
				(justify mirror)
			)
		)
		(property "Value" "*"
			(at -1.1811 -2.8194 180)
			(unlocked yes)
			(layer "B.Fab")
			(hide yes)
			(effects
				(font
					(size 1.27 1.016)
					(thickness 0.1524)
				)
				(justify mirror)
			)
		)
		(property "Device Type" "SC1U10V2KX-4-GP_SMD-BCG6-SC1U1A"
			(at -1.1811 -4.3434 180)
			(unlocked yes)
			(layer "B.Fab")
			(hide yes)
			(effects
				(font
					(size 1.27 1.016)
					(thickness 0.1524)
				)
				(justify mirror)
			)
		)
		(duplicate_pad_numbers_are_jumpers no)
		(fp_rect
			(start 0.4318 0.9525)
			(end -0.4318 -0.9525)
			(stroke
				(width 0)
				(type default)
			)
			(fill no)
			(layer "B.CrtYd")
		)
		(fp_rect
			(start 0.4318 0.9525)
			(end -0.4318 -0.9525)
			(stroke
				(width 0)
				(type default)
			)
			(fill no)
			(layer "B.Fab")
		)
		(pad "1" smd custom
			(at 0 -0.4445)
			(size 0.1524 0.1524)
			(layers "B.Cu" "B.Mask" "B.Paste")
			(net "P5V_STBY")
			(options
				(clearance outline)
				(anchor circle)
			)
			(primitives
				(gr_poly
					(pts
						(arc
							(start 0.3048 0.2032)
							(mid 0.275042 0.275042)
							(end 0.2032 0.3048)
						)
						(arc
							(start -0.2032 0.3048)
							(mid -0.275042 0.275042)
							(end -0.3048 0.2032)
						)
						(arc
							(start -0.3048 -0.2032)
							(mid -0.275042 -0.275042)
							(end -0.2032 -0.3048)
						)
						(arc
							(start 0.2032 -0.3048)
							(mid 0.275042 -0.275042)
							(end 0.3048 -0.2032)
						)
					)
					(width 0)
					(fill yes)
				)
			)
		)
		(pad "2" smd custom
			(at 0 0.4445)
			(size 0.1524 0.1524)
			(layers "B.Cu" "B.Mask" "B.Paste")
			(net "GND")
			(options
				(clearance outline)
				(anchor circle)
			)
			(primitives
				(gr_poly
					(pts
						(arc
							(start 0.3048 0.2032)
							(mid 0.275042 0.275042)
							(end 0.2032 0.3048)
						)
						(arc
							(start -0.2032 0.3048)
							(mid -0.275042 0.275042)
							(end -0.3048 0.2032)
						)
						(arc
							(start -0.3048 -0.2032)
							(mid -0.275042 -0.275042)
							(end -0.2032 -0.3048)
						)
						(arc
							(start 0.2032 -0.3048)
							(mid 0.275042 -0.275042)
							(end 0.3048 -0.2032)
						)
					)
					(width 0)
					(fill yes)
				)
			)
		)
	)
	(footprint ""
		(layer "B.Cu")
		(at 378.587 -82.677 -90)
		(property "Reference" "C7W1"
			(at 0.8382 -0.67818 270)
			(unlocked yes)
			(layer "B.SilkS")
			(effects
				(font
					(size 0.4064 0.254)
					(thickness 0.1524)
				)
				(justify left mirror)
			)
		)
		(property "Value" ""
			(at 0 0 90)
			(layer "B.Fab")
			(effects
				(font
					(size 1.27 1.27)
				)
				(justify mirror)
			)
		)
		(duplicate_pad_numbers_are_jumpers no)
		(fp_poly
			(pts
				(xy -0.3048 -0.1016) (xy -0.3048 0.9906) (xy 0.3048 0.9906) (xy 0.3048 -0.1016)
			)
			(stroke
				(width 0)
				(type default)
			)
			(fill no)
			(layer "B.CrtYd")
		)
		(fp_line
			(start -0.3048 0.9906)
			(end -0.3048 -0.1016)
			(stroke
				(width 0.1)
				(type default)
			)
			(layer "B.Fab")
		)
		(fp_line
			(start 0.3048 0.9906)
			(end -0.3048 0.9906)
			(stroke
				(width 0.1)
				(type default)
			)
			(layer "B.Fab")
		)
		(fp_line
			(start -0.3048 -0.1016)
			(end 0.3048 -0.1016)
			(stroke
				(width 0.1)
				(type default)
			)
			(layer "B.Fab")
		)
		(fp_line
			(start 0.3048 -0.1016)
			(end 0.3048 0.9906)
			(stroke
				(width 0.1)
				(type default)
			)
			(layer "B.Fab")
		)
		(pad "1" smd rect
			(at 0 0 90)
			(size 0.508 0.508)
			(layers "B.Cu" "B.Mask" "B.Paste")
			(net "P3V3_STBY")
		)
		(pad "2" smd rect
			(at 0 0.889 90)
			(size 0.508 0.508)
			(layers "B.Cu" "B.Mask" "B.Paste")
			(net "GND")
		)
		(zone
			(layer "B.Cu")
			(hatch none 0.5)
			(connect_pads
				(clearance 0)
			)
			(min_thickness 0.25)
			(keepout
				(tracks not_allowed)
				(vias allowed)
				(pads allowed)
				(copperpour not_allowed)
				(footprints allowed)
			)
			(placement
				(enabled no)
				(sheetname "")
			)
			(fill
				(thermal_gap 0.5)
				(thermal_bridge_width 0.5)
				(island_removal_mode 0)
			)
			(polygon
				(pts
					(xy 377.952 -82.423) (xy 377.952 -82.931) (xy 378.333 -82.931) (xy 378.333 -82.423)
				)
			)
		)
		(zone
			(layer "B.Cu")
			(hatch none 0.5)
			(connect_pads
				(clearance 0)
			)
			(min_thickness 0.25)
			(keepout
				(tracks allowed)
				(vias not_allowed)
				(pads allowed)
				(copperpour not_allowed)
				(footprints allowed)
			)
			(placement
				(enabled no)
				(sheetname "")
			)
			(fill
				(thermal_gap 0.5)
				(thermal_bridge_width 0.5)
				(island_removal_mode 0)
			)
			(polygon
				(pts
					(xy 378.333 -82.423) (xy 378.333 -82.931) (xy 377.952 -82.931) (xy 377.952 -82.423)
				)
			)
		)
	)
	(footprint ""
		(layer "B.Cu")
		(at 272.861532 -12.954 90)
		(property "Reference" "C5G48"
			(at -1.14681 0.76708 180)
			(unlocked yes)
			(layer "B.SilkS")
			(effects
				(font
					(size 0.7874 0.5842)
					(thickness 0.1524)
				)
				(justify mirror)
			)
		)
		(property "Value" ""
			(at 0 0 90)
			(layer "B.Fab")
			(effects
				(font
					(size 1.27 1.27)
				)
				(justify mirror)
			)
		)
		(duplicate_pad_numbers_are_jumpers no)
		(fp_rect
			(start -0.4953 -0.2032)
			(end 0.4953 1.6002)
			(stroke
				(width 0)
				(type default)
			)
			(fill no)
			(layer "B.CrtYd")
		)
		(fp_line
			(start 0.4953 -0.2032)
			(end -0.4953 -0.2032)
			(stroke
				(width 0.1)
				(type default)
			)
			(layer "B.Fab")
		)
		(fp_line
			(start -0.4953 -0.2032)
			(end -0.4953 1.6002)
			(stroke
				(width 0.1)
				(type default)
			)
			(layer "B.Fab")
		)
		(fp_line
			(start 0.4953 1.6002)
			(end 0.4953 -0.2032)
			(stroke
				(width 0.1)
				(type default)
			)
			(layer "B.Fab")
		)
		(fp_line
			(start -0.4953 1.6002)
			(end 0.4953 1.6002)
			(stroke
				(width 0.1)
				(type default)
			)
			(layer "B.Fab")
		)
		(pad "1" smd rect
			(at 0 0 270)
			(size 0.762 0.889)
			(layers "B.Cu" "B.Mask" "B.Paste")
			(net "PVDDQ_ABC")
		)
		(pad "2" smd rect
			(at 0 1.397 270)
			(size 0.762 0.889)
			(layers "B.Cu" "B.Mask" "B.Paste")
			(net "GND")
		)
		(zone
			(layer "B.Cu")
			(hatch none 0.5)
			(connect_pads
				(clearance 0)
			)
			(min_thickness 0.25)
			(keepout
				(tracks not_allowed)
				(vias allowed)
				(pads allowed)
				(copperpour not_allowed)
				(footprints allowed)
			)
			(placement
				(enabled no)
				(sheetname "")
			)
			(fill
				(thermal_gap 0.5)
				(thermal_bridge_width 0.5)
				(island_removal_mode 0)
			)
			(polygon
				(pts
					(xy 273.306032 -12.573) (xy 273.814032 -12.573) (xy 273.814032 -13.335) (xy 273.306032 -13.335)
				)
			)
		)
	)
	(footprint ""
		(layer "B.Cu")
		(at 496.34648 -130.52552)
		(property "Reference" "C1M31"
			(at 0 0 0)
			(layer "B.SilkS")
			(hide yes)
			(effects
				(font
					(size 1.27 1.27)
				)
				(justify mirror)
			)
		)
		(property "Value" ""
			(at 0 0 0)
			(layer "B.Fab")
			(effects
				(font
					(size 1.27 1.27)
				)
				(justify mirror)
			)
		)
		(duplicate_pad_numbers_are_jumpers no)
		(fp_poly
			(pts
				(xy -0.3048 -0.1016) (xy -0.3048 0.9906) (xy 0.3048 0.9906) (xy 0.3048 -0.1016)
			)
			(stroke
				(width 0)
				(type default)
			)
			(fill no)
			(layer "B.CrtYd")
		)
		(fp_line
			(start -0.3048 -0.1016)
			(end 0.3048 -0.1016)
			(stroke
				(width 0.1)
				(type default)
			)
			(layer "B.Fab")
		)
		(fp_line
			(start -0.3048 0.9906)
			(end -0.3048 -0.1016)
			(stroke
				(width 0.1)
				(type default)
			)
			(layer "B.Fab")
		)
		(fp_line
			(start 0.3048 -0.1016)
			(end 0.3048 0.9906)
			(stroke
				(width 0.1)
				(type default)
			)
			(layer "B.Fab")
		)
		(fp_line
			(start 0.3048 0.9906)
			(end -0.3048 0.9906)
			(stroke
				(width 0.1)
				(type default)
			)
			(layer "B.Fab")
		)
		(pad "1" smd rect
			(at 0 0 180)
			(size 0.508 0.508)
			(layers "B.Cu" "B.Mask" "B.Paste")
			(net "P3V3_STBY")
		)
		(pad "2" smd rect
			(at 0 0.889 180)
			(size 0.508 0.508)
			(layers "B.Cu" "B.Mask" "B.Paste")
			(net "GND")
		)
		(zone
			(layer "B.Cu")
			(hatch none 0.5)
			(connect_pads
				(clearance 0)
			)
			(min_thickness 0.25)
			(keepout
				(tracks allowed)
				(vias not_allowed)
				(pads allowed)
				(copperpour not_allowed)
				(footprints allowed)
			)
			(placement
				(enabled no)
				(sheetname "")
			)
			(fill
				(thermal_gap 0.5)
				(thermal_bridge_width 0.5)
				(island_removal_mode 0)
			)
			(polygon
				(pts
					(xy 496.60048 -130.27152) (xy 496.09248 -130.27152) (xy 496.09248 -129.89052) (xy 496.60048 -129.89052)
				)
			)
		)
		(zone
			(layer "B.Cu")
			(hatch none 0.5)
			(connect_pads
				(clearance 0)
			)
			(min_thickness 0.25)
			(keepout
				(tracks not_allowed)
				(vias allowed)
				(pads allowed)
				(copperpour not_allowed)
				(footprints allowed)
			)
			(placement
				(enabled no)
				(sheetname "")
			)
			(fill
				(thermal_gap 0.5)
				(thermal_bridge_width 0.5)
				(island_removal_mode 0)
			)
			(polygon
				(pts
					(xy 496.60048 -129.89052) (xy 496.09248 -129.89052) (xy 496.09248 -130.27152) (xy 496.60048 -130.27152)
				)
			)
		)
	)
	(footprint ""
		(layer "B.Cu")
		(at 112.0775 -126.08306 90)
		(property "Reference" "C8M11"
			(at 0 0 90)
			(layer "B.SilkS")
			(hide yes)
			(effects
				(font
					(size 1.27 1.27)
				)
				(justify mirror)
			)
		)
		(property "Value" ""
			(at 0 0 90)
			(layer "B.Fab")
			(effects
				(font
					(size 1.27 1.27)
				)
				(justify mirror)
			)
		)
		(duplicate_pad_numbers_are_jumpers no)
		(fp_poly
			(pts
				(xy 0.7239 -0.2159) (xy -0.7239 -0.2159) (xy -0.7239 1.9939) (xy 0.7239 1.9939)
			)
			(stroke
				(width 0)
				(type default)
			)
			(fill no)
			(layer "B.CrtYd")
		)
		(fp_line
			(start 0.7239 -0.2159)
			(end 0.7239 1.9939)
			(stroke
				(width 0.1)
				(type default)
			)
			(layer "B.Fab")
		)
		(fp_line
			(start -0.7239 -0.2159)
			(end 0.7239 -0.2159)
			(stroke
				(width 0.1)
				(type default)
			)
			(layer "B.Fab")
		)
		(fp_line
			(start 0.7239 1.9939)
			(end -0.7239 1.9939)
			(stroke
				(width 0.1)
				(type default)
			)
			(layer "B.Fab")
		)
		(fp_line
			(start -0.7239 1.9939)
			(end -0.7239 -0.2159)
			(stroke
				(width 0.1)
				(type default)
			)
			(layer "B.Fab")
		)
		(pad "1" smd rect
			(at 0 0 270)
			(size 1.27 1.016)
			(layers "B.Cu" "B.Mask" "B.Paste")
			(net "PVDDQ_KLM")
		)
		(pad "2" smd rect
			(at 0 1.778 270)
			(size 1.27 1.016)
			(layers "B.Cu" "B.Mask" "B.Paste")
			(net "GND")
		)
		(zone
			(layer "B.Cu")
			(hatch none 0.5)
			(connect_pads
				(clearance 0)
			)
			(min_thickness 0.25)
			(keepout
				(tracks not_allowed)
				(vias allowed)
				(pads allowed)
				(copperpour not_allowed)
				(footprints allowed)
			)
			(placement
				(enabled no)
				(sheetname "")
			)
			(fill
				(thermal_gap 0.5)
				(thermal_bridge_width 0.5)
				(island_removal_mode 0)
			)
			(polygon
				(pts
					(xy 112.5855 -126.71806) (xy 112.5855 -125.44806) (xy 113.3475 -125.44806) (xy 113.3475 -126.71806)
				)
			)
		)
	)
	(footprint ""
		(layer "B.Cu")
		(at 277.217886 -79.60614 180)
		(property "Reference" "C4P3"
			(at 0 0 0)
			(layer "B.SilkS")
			(hide yes)
			(effects
				(font
					(size 1.27 1.27)
				)
				(justify mirror)
			)
		)
		(property "Value" ""
			(at 0 0 0)
			(layer "B.Fab")
			(effects
				(font
					(size 1.27 1.27)
				)
				(justify mirror)
			)
		)
		(duplicate_pad_numbers_are_jumpers no)
		(fp_poly
			(pts
				(xy 0.7239 -0.2159) (xy -0.7239 -0.2159) (xy -0.7239 1.9939) (xy 0.7239 1.9939)
			)
			(stroke
				(width 0)
				(type default)
			)
			(fill no)
			(layer "B.CrtYd")
		)
		(fp_line
			(start 0.7239 1.9939)
			(end -0.7239 1.9939)
			(stroke
				(width 0.1)
				(type default)
			)
			(layer "B.Fab")
		)
		(fp_line
			(start 0.7239 -0.2159)
			(end 0.7239 1.9939)
			(stroke
				(width 0.1)
				(type default)
			)
			(layer "B.Fab")
		)
		(fp_line
			(start -0.7239 1.9939)
			(end -0.7239 -0.2159)
			(stroke
				(width 0.1)
				(type default)
			)
			(layer "B.Fab")
		)
		(fp_line
			(start -0.7239 -0.2159)
			(end 0.7239 -0.2159)
			(stroke
				(width 0.1)
				(type default)
			)
			(layer "B.Fab")
		)
		(pad "1" smd rect
			(at 0 0)
			(size 1.27 1.016)
			(layers "B.Cu" "B.Mask" "B.Paste")
			(net "PVCCMCP_CPU0")
		)
		(pad "2" smd rect
			(at 0 1.778)
			(size 1.27 1.016)
			(layers "B.Cu" "B.Mask" "B.Paste")
			(net "GND")
		)
		(zone
			(layer "B.Cu")
			(hatch none 0.5)
			(connect_pads
				(clearance 0)
			)
			(min_thickness 0.25)
			(keepout
				(tracks not_allowed)
				(vias allowed)
				(pads allowed)
				(copperpour not_allowed)
				(footprints allowed)
			)
			(placement
				(enabled no)
				(sheetname "")
			)
			(fill
				(thermal_gap 0.5)
				(thermal_bridge_width 0.5)
				(island_removal_mode 0)
			)
			(polygon
				(pts
					(xy 276.582886 -80.11414) (xy 277.852886 -80.11414) (xy 277.852886 -80.87614) (xy 276.582886 -80.87614)
				)
			)
		)
	)
	(footprint ""
		(layer "B.Cu")
		(at 417.746434 -34.186368 -90)
		(property "Reference" "C25W29"
			(at -0.97536 0.76708 0)
			(unlocked yes)
			(layer "B.SilkS")
			(effects
				(font
					(size 0.4064 0.254)
					(thickness 0.1524)
				)
				(justify mirror)
			)
		)
		(property "Value" ""
			(at 0 0 90)
			(layer "B.Fab")
			(effects
				(font
					(size 1.27 1.27)
				)
				(justify mirror)
			)
		)
		(duplicate_pad_numbers_are_jumpers no)
		(fp_poly
			(pts
				(xy 0.4953 -0.2032) (xy -0.4953 -0.2032) (xy -0.4953 1.6002) (xy 0.4953 1.6002)
			)
			(stroke
				(width 0)
				(type default)
			)
			(fill no)
			(layer "B.CrtYd")
		)
		(fp_line
			(start -0.4953 1.6002)
			(end 0.4953 1.6002)
			(stroke
				(width 0.1)
				(type default)
			)
			(layer "B.Fab")
		)
		(fp_line
			(start 0.4953 1.6002)
			(end 0.4953 -0.2032)
			(stroke
				(width 0.1)
				(type default)
			)
			(layer "B.Fab")
		)
		(fp_line
			(start -0.4953 -0.2032)
			(end -0.4953 1.6002)
			(stroke
				(width 0.1)
				(type default)
			)
			(layer "B.Fab")
		)
		(fp_line
			(start 0.4953 -0.2032)
			(end -0.4953 -0.2032)
			(stroke
				(width 0.1)
				(type default)
			)
			(layer "B.Fab")
		)
		(pad "1" smd rect
			(at 0 0 90)
			(size 0.762 0.889)
			(layers "B.Cu" "B.Mask" "B.Paste")
			(net "P1V15_AUX_BMC")
		)
		(pad "2" smd rect
			(at 0 1.397 90)
			(size 0.762 0.889)
			(layers "B.Cu" "B.Mask" "B.Paste")
			(net "GND")
		)
		(zone
			(layer "B.Cu")
			(hatch none 0.5)
			(connect_pads
				(clearance 0)
			)
			(min_thickness 0.25)
			(keepout
				(tracks not_allowed)
				(vias allowed)
				(pads allowed)
				(copperpour not_allowed)
				(footprints allowed)
			)
			(placement
				(enabled no)
				(sheetname "")
			)
			(fill
				(thermal_gap 0.5)
				(thermal_bridge_width 0.5)
				(island_removal_mode 0)
			)
			(polygon
				(pts
					(xy 417.301934 -33.805368) (xy 417.301934 -34.567368) (xy 416.793934 -34.567368) (xy 416.793934 -33.805368)
				)
			)
		)
	)
	(footprint ""
		(layer "B.Cu")
		(at 167.288718 -74.135234)
		(property "Reference" "R6P22"
			(at 0 0 0)
			(layer "B.SilkS")
			(hide yes)
			(effects
				(font
					(size 1.27 1.27)
				)
				(justify mirror)
			)
		)
		(property "Value" ""
			(at 0 0 0)
			(layer "B.Fab")
			(effects
				(font
					(size 1.27 1.27)
				)
				(justify mirror)
			)
		)
		(duplicate_pad_numbers_are_jumpers no)
		(fp_poly
			(pts
				(xy 0.2794 -0.1016) (xy -0.2794 -0.1016) (xy -0.2794 0.9906) (xy 0.2794 0.9906)
			)
			(stroke
				(width 0)
				(type default)
			)
			(fill no)
			(layer "B.CrtYd")
		)
		(fp_line
			(start -0.2794 -0.1016)
			(end 0.2794 -0.1016)
			(stroke
				(width 0.1)
				(type default)
			)
			(layer "B.Fab")
		)
		(fp_line
			(start -0.2794 0.9906)
			(end -0.2794 -0.1016)
			(stroke
				(width 0.1)
				(type default)
			)
			(layer "B.Fab")
		)
		(fp_line
			(start 0.2794 -0.1016)
			(end 0.2794 0.9906)
			(stroke
				(width 0.1)
				(type default)
			)
			(layer "B.Fab")
		)
		(fp_line
			(start 0.2794 0.9906)
			(end -0.2794 0.9906)
			(stroke
				(width 0.1)
				(type default)
			)
			(layer "B.Fab")
		)
		(pad "1" smd rect
			(at 0 0 180)
			(size 0.508 0.508)
			(layers "B.Cu" "B.Mask" "B.Paste")
			(net "FM_HBW_BYPASS_LOWBW_N")
		)
		(pad "2" smd rect
			(at 0 0.889 180)
			(size 0.508 0.508)
			(layers "B.Cu" "B.Mask" "B.Paste")
			(net "GND")
		)
		(zone
			(layer "B.Cu")
			(hatch none 0.5)
			(connect_pads
				(clearance 0)
			)
			(min_thickness 0.25)
			(keepout
				(tracks allowed)
				(vias not_allowed)
				(pads allowed)
				(copperpour not_allowed)
				(footprints allowed)
			)
			(placement
				(enabled no)
				(sheetname "")
			)
			(fill
				(thermal_gap 0.5)
				(thermal_bridge_width 0.5)
				(island_removal_mode 0)
			)
			(polygon
				(pts
					(xy 167.542718 -73.881234) (xy 167.034718 -73.881234) (xy 167.034718 -73.500234) (xy 167.542718 -73.500234)
				)
			)
		)
		(zone
			(layer "B.Cu")
			(hatch none 0.5)
			(connect_pads
				(clearance 0)
			)
			(min_thickness 0.25)
			(keepout
				(tracks not_allowed)
				(vias allowed)
				(pads allowed)
				(copperpour not_allowed)
				(footprints allowed)
			)
			(placement
				(enabled no)
				(sheetname "")
			)
			(fill
				(thermal_gap 0.5)
				(thermal_bridge_width 0.5)
				(island_removal_mode 0)
			)
			(polygon
				(pts
					(xy 167.542718 -73.500234) (xy 167.034718 -73.500234) (xy 167.034718 -73.881234) (xy 167.542718 -73.881234)
				)
			)
		)
	)
)
